# T6G (Grand Teton) — schematic netlist excerpt (pin names and nets, part order shuffled) for the footprints in the layout excerpt that follows; sources: Cadence DE-HDL packaged netlist, KiCad conversion of 04192023_DAF0TMB3IC0_F0TG_MB_C_brd_V02_OCP.brd

C2668  Q_CAP  22UF 4V 20% X6S  pkg C0402  page 75 : A = PVDD18_S5_P1 ; B = GND
C2459  Q_CAP  22UF 4V 20% X6S  pkg C0402  page 74 : A = PVDDCR_SOC_P1 ; B = GND

(kicad_pcb
	(version 20260206)
	(generator "pcbnew")
	(generator_version "10.0")
	(general
		(thickness 1.6)
		(legacy_teardrops no)
	)
	(paper "A4")
	(title_block
		(title "04192023_DAF0TMB3IC0_F0TG_MB_C_brd_V02_OCP.brd")
		(comment 1 "Grand Teton / footprints 8277-8278 of 8354")
	)
	(layers
		(0 "F.Cu" signal "TOP")
		(4 "In1.Cu" signal "GND")
		(6 "In2.Cu" signal "IN1")
		(8 "In3.Cu" signal "GND1")
		(10 "In4.Cu" signal "IN2")
		(12 "In5.Cu" signal "GND2")
		(14 "In6.Cu" signal "IN3")
		(16 "In7.Cu" signal "GND3")
		(18 "In8.Cu" signal "VCC")
		(20 "In9.Cu" signal "VCC1")
		(22 "In10.Cu" signal "GND4")
		(24 "In11.Cu" signal "IN4")
		(26 "In12.Cu" signal "GND5")
		(28 "In13.Cu" signal "IN5")
		(30 "In14.Cu" signal "GND6")
		(32 "In15.Cu" signal "IN6")
		(34 "In16.Cu" signal "GND7")
		(2 "B.Cu" signal "BOTTOM")
		(9 "F.Adhes" user "F.Adhesive")
		(11 "B.Adhes" user "B.Adhesive")
		(13 "F.Paste" user "Package Geometry/Pastemask Top")
		(15 "B.Paste" user "Package Geometry/Pastemask Bottom")
		(5 "F.SilkS" user "Ref Des/Silkscreen Top")
		(7 "B.SilkS" user "Ref Des/Silkscreen Bottom")
		(1 "F.Mask" user "Board Geometry/Soldermask Top")
		(3 "B.Mask" user "Board Geometry/Soldermask Bottom")
		(17 "Dwgs.User" user "User.Drawings")
		(19 "Cmts.User" user "User.Comments")
		(21 "Eco1.User" user "User.Eco1")
		(23 "Eco2.User" user "User.Eco2")
		(25 "Edge.Cuts" user "Board Geometry/Outline")
		(27 "Margin" user)
		(31 "F.CrtYd" user "Package Geometry/Place Bound Top")
		(29 "B.CrtYd" user "Package Geometry/Place Bound Bottom")
		(35 "F.Fab" user "Ref Des/Assembly Top")
		(33 "B.Fab" user "Ref Des/Assembly Bottom")
	)
	(footprint ""
		(layer "B.Cu")
		(at 109.895386 -251.781564)
		(property "Reference" "C2459"
			(at 0 0 0)
			(layer "B.SilkS")
			(hide yes)
			(effects
				(font
					(size 1.27 1.27)
				)
				(justify mirror)
			)
		)
		(property "Value" ""
			(at 0 0 0)
			(layer "B.Fab")
			(effects
				(font
					(size 1.27 1.27)
				)
				(justify mirror)
			)
		)
		(duplicate_pad_numbers_are_jumpers no)
		(fp_line
			(start -0.7874 -0.4064)
			(end -0.7874 0.4064)
			(stroke
				(width 0.1524)
				(type default)
			)
			(layer "B.SilkS")
		)
		(fp_line
			(start -0.7874 0.4064)
			(end 0.7874 0.4064)
			(stroke
				(width 0.1524)
				(type default)
			)
			(layer "B.SilkS")
		)
		(fp_line
			(start 0.7874 -0.4064)
			(end -0.7874 -0.4064)
			(stroke
				(width 0.1524)
				(type default)
			)
			(layer "B.SilkS")
		)
		(fp_line
			(start 0.7874 0.4064)
			(end 0.7874 -0.4064)
			(stroke
				(width 0.1524)
				(type default)
			)
			(layer "B.SilkS")
		)
		(fp_line
			(start -0.67945 -0.3048)
			(end -0.67945 0.3048)
			(stroke
				(width 0.1)
				(type default)
			)
			(layer "B.Fab")
		)
		(fp_line
			(start -0.67945 0.3048)
			(end -0.120396 0.3048)
			(stroke
				(width 0.1)
				(type default)
			)
			(layer "B.Fab")
		)
		(fp_line
			(start -0.12065 -0.3048)
			(end -0.67945 -0.3048)
			(stroke
				(width 0.1)
				(type default)
			)
			(layer "B.Fab")
		)
		(fp_line
			(start -0.12065 -0.2794)
			(end -0.12065 -0.3048)
			(stroke
				(width 0.1)
				(type default)
			)
			(layer "B.Fab")
		)
		(fp_line
			(start -0.120396 0.2794)
			(end 0.12065 0.2794)
			(stroke
				(width 0.1)
				(type default)
			)
			(layer "B.Fab")
		)
		(fp_line
			(start -0.120396 0.3048)
			(end -0.120396 0.2794)
			(stroke
				(width 0.1)
				(type default)
			)
			(layer "B.Fab")
		)
		(fp_line
			(start 0.12065 -0.305054)
			(end 0.12065 -0.2794)
			(stroke
				(width 0.1)
				(type default)
			)
			(layer "B.Fab")
		)
		(fp_line
			(start 0.12065 -0.2794)
			(end -0.12065 -0.2794)
			(stroke
				(width 0.1)
				(type default)
			)
			(layer "B.Fab")
		)
		(fp_line
			(start 0.12065 0.2794)
			(end 0.12065 0.3048)
			(stroke
				(width 0.1)
				(type default)
			)
			(layer "B.Fab")
		)
		(fp_line
			(start 0.12065 0.3048)
			(end 0.67945 0.3048)
			(stroke
				(width 0.1)
				(type default)
			)
			(layer "B.Fab")
		)
		(fp_line
			(start 0.67945 -0.305054)
			(end 0.12065 -0.305054)
			(stroke
				(width 0.1)
				(type default)
			)
			(layer "B.Fab")
		)
		(fp_line
			(start 0.67945 0.3048)
			(end 0.67945 -0.305054)
			(stroke
				(width 0.1)
				(type default)
			)
			(layer "B.Fab")
		)
		(pad "1" smd circle
			(at 0.40005 0 180)
			(size 0 0)
			(layers "B.Cu" "B.Mask" "B.Paste")
			(net "PVDDCR_SOC_P1")
		)
		(pad "2" smd circle
			(at -0.40005 0 180)
			(size 0 0)
			(layers "B.Cu" "B.Mask" "B.Paste")
			(net "GND")
		)
	)
	(footprint ""
		(layer "B.Cu")
		(at 108.360464 -257.750564 180)
		(property "Reference" "C2668"
			(at 0 0 0)
			(layer "B.SilkS")
			(hide yes)
			(effects
				(font
					(size 1.27 1.27)
				)
				(justify mirror)
			)
		)
		(property "Value" ""
			(at 0 0 0)
			(layer "B.Fab")
			(effects
				(font
					(size 1.27 1.27)
				)
				(justify mirror)
			)
		)
		(duplicate_pad_numbers_are_jumpers no)
		(fp_line
			(start 0.7874 0.4064)
			(end 0.7874 -0.4064)
			(stroke
				(width 0.1524)
				(type default)
			)
			(layer "B.SilkS")
		)
		(fp_line
			(start 0.7874 -0.4064)
			(end -0.7874 -0.4064)
			(stroke
				(width 0.1524)
				(type default)
			)
			(layer "B.SilkS")
		)
		(fp_line
			(start -0.7874 0.4064)
			(end 0.7874 0.4064)
			(stroke
				(width 0.1524)
				(type default)
			)
			(layer "B.SilkS")
		)
		(fp_line
			(start -0.7874 -0.4064)
			(end -0.7874 0.4064)
			(stroke
				(width 0.1524)
				(type default)
			)
			(layer "B.SilkS")
		)
		(fp_line
			(start 0.67945 0.3048)
			(end 0.67945 -0.305054)
			(stroke
				(width 0.1)
				(type default)
			)
			(layer "B.Fab")
		)
		(fp_line
			(start 0.67945 -0.305054)
			(end 0.12065 -0.305054)
			(stroke
				(width 0.1)
				(type default)
			)
			(layer "B.Fab")
		)
		(fp_line
			(start 0.12065 0.3048)
			(end 0.67945 0.3048)
			(stroke
				(width 0.1)
				(type default)
			)
			(layer "B.Fab")
		)
		(fp_line
			(start 0.12065 0.2794)
			(end 0.12065 0.3048)
			(stroke
				(width 0.1)
				(type default)
			)
			(layer "B.Fab")
		)
		(fp_line
			(start 0.12065 -0.2794)
			(end -0.12065 -0.2794)
			(stroke
				(width 0.1)
				(type default)
			)
			(layer "B.Fab")
		)
		(fp_line
			(start 0.12065 -0.305054)
			(end 0.12065 -0.2794)
			(stroke
				(width 0.1)
				(type default)
			)
			(layer "B.Fab")
		)
		(fp_line
			(start -0.120396 0.3048)
			(end -0.120396 0.2794)
			(stroke
				(width 0.1)
				(type default)
			)
			(layer "B.Fab")
		)
		(fp_line
			(start -0.120396 0.2794)
			(end 0.12065 0.2794)
			(stroke
				(width 0.1)
				(type default)
			)
			(layer "B.Fab")
		)
		(fp_line
			(start -0.12065 -0.2794)
			(end -0.12065 -0.3048)
			(stroke
				(width 0.1)
				(type default)
			)
			(layer "B.Fab")
		)
		(fp_line
			(start -0.12065 -0.3048)
			(end -0.67945 -0.3048)
			(stroke
				(width 0.1)
				(type default)
			)
			(layer "B.Fab")
		)
		(fp_line
			(start -0.67945 0.3048)
			(end -0.120396 0.3048)
			(stroke
				(width 0.1)
				(type default)
			)
			(layer "B.Fab")
		)
		(fp_line
			(start -0.67945 -0.3048)
			(end -0.67945 0.3048)
			(stroke
				(width 0.1)
				(type default)
			)
			(layer "B.Fab")
		)
		(pad "1" smd circle
			(at 0.40005 0)
			(size 0 0)
			(layers "B.Cu" "B.Mask" "B.Paste")
			(net "PVDD18_S5_P1")
		)
		(pad "2" smd circle
			(at -0.40005 0)
			(size 0 0)
			(layers "B.Cu" "B.Mask" "B.Paste")
			(net "GND")
		)
	)
)
